(kicad_pcb
	(version 20260206)
	(generator "pcbnew")
	(generator_version "10.0")
	(general
		(thickness 1.6)
		(legacy_teardrops no)
	)
	(paper "A4")
	(title_block
		(title "peb — Lightning_PEB_BRD.brd")
		(comment 1 "Lightning (Wiwynn / Facebook NVMe JBOF) / footprints 1871-1879 of 2563")
	)
	(layers
		(0 "F.Cu" signal "TOP")
		(4 "In1.Cu" signal "L2GND")
		(6 "In2.Cu" signal "L3")
		(8 "In3.Cu" signal "L4VCC")
		(10 "In4.Cu" signal "L5VCC")
		(12 "In5.Cu" signal "L6")
		(14 "In6.Cu" signal "L7GND")
		(2 "B.Cu" signal "BOTTOM")
		(9 "F.Adhes" user "F.Adhesive")
		(11 "B.Adhes" user "B.Adhesive")
		(13 "F.Paste" user "Package Geometry/Pastemask Top")
		(15 "B.Paste" user "Package Geometry/Pastemask Bottom")
		(5 "F.SilkS" user "Ref Des/Silkscreen Top")
		(7 "B.SilkS" user "Ref Des/Silkscreen Bottom")
		(1 "F.Mask" user "Board Geometry/Soldermask Top")
		(3 "B.Mask" user "Board Geometry/Soldermask Bottom")
		(17 "Dwgs.User" user "User.Drawings")
		(19 "Cmts.User" user "User.Comments")
		(21 "Eco1.User" user "User.Eco1")
		(23 "Eco2.User" user "User.Eco2")
		(25 "Edge.Cuts" user "Board Geometry/Outline")
		(27 "Margin" user)
		(31 "F.CrtYd" user "Package Geometry/Place Bound Top")
		(29 "B.CrtYd" user "Package Geometry/Place Bound Bottom")
		(35 "F.Fab" user "Ref Des/Assembly Top")
		(33 "B.Fab" user "Ref Des/Assembly Bottom")
	)
	(footprint ""
		(layer "B.Cu")
		(at 71.731124 -183.235092)
		(property "Reference" "R4102"
			(at 0 0 0)
			(layer "B.SilkS")
			(hide yes)
			(effects
				(font
					(size 1.27 1.27)
				)
				(justify mirror)
			)
		)
		(property "Value" "4K7R2F-GP"
			(at -0.064008 -3.993896 0)
			(unlocked yes)
			(layer "B.Fab")
			(hide yes)
			(effects
				(font
					(size 1.016 1.016)
					(thickness 0.1524)
				)
				(justify mirror)
			)
		)
		(property "Device Type" "R402H16"
			(at -0.064008 -5.517896 0)
			(unlocked yes)
			(layer "B.Fab")
			(hide yes)
			(effects
				(font
					(size 1.016 1.016)
					(thickness 0.1524)
				)
				(justify mirror)
			)
		)
		(duplicate_pad_numbers_are_jumpers no)
		(fp_line
			(start -0.508 -0.9398)
			(end 0.508 -0.9398)
			(stroke
				(width 0.1524)
				(type default)
			)
			(layer "B.SilkS")
		)
		(fp_line
			(start 0.508 -0.9398)
			(end 0.508 0.9398)
			(stroke
				(width 0.1524)
				(type default)
			)
			(layer "B.SilkS")
		)
		(fp_rect
			(start 0.508 0.9398)
			(end -0.508 -0.9398)
			(stroke
				(width 0)
				(type default)
			)
			(fill no)
			(layer "B.CrtYd")
		)
		(fp_rect
			(start 0.508 0.9398)
			(end -0.508 -0.9398)
			(stroke
				(width 0)
				(type default)
			)
			(fill no)
			(layer "B.Fab")
		)
		(pad "1" smd custom
			(at 0 -0.4445 180)
			(size 0.1397 0.1397)
			(layers "B.Cu" "B.Mask" "B.Paste")
			(net "SSD_PRSNT#0")
			(options
				(clearance outline)
				(anchor circle)
			)
			(primitives
				(gr_poly
					(pts
						(arc
							(start -0.1778 0.2794)
							(mid -0.249642 0.249642)
							(end -0.2794 0.1778)
						)
						(arc
							(start -0.2794 -0.1778)
							(mid -0.249642 -0.249642)
							(end -0.1778 -0.2794)
						)
						(arc
							(start 0.1778 -0.2794)
							(mid 0.249642 -0.249642)
							(end 0.2794 -0.1778)
						)
						(arc
							(start 0.2794 0.1778)
							(mid 0.249642 0.249642)
							(end 0.1778 0.2794)
						)
					)
					(width 0)
					(fill yes)
				)
			)
		)
		(pad "2" smd custom
			(at 0 0.4445 180)
			(size 0.1397 0.1397)
			(layers "B.Cu" "B.Mask" "B.Paste")
			(net "P3V3_STBY")
			(options
				(clearance outline)
				(anchor circle)
			)
			(primitives
				(gr_poly
					(pts
						(arc
							(start -0.1778 0.2794)
							(mid -0.249642 0.249642)
							(end -0.2794 0.1778)
						)
						(arc
							(start -0.2794 -0.1778)
							(mid -0.249642 -0.249642)
							(end -0.1778 -0.2794)
						)
						(arc
							(start 0.1778 -0.2794)
							(mid 0.249642 -0.249642)
							(end 0.2794 -0.1778)
						)
						(arc
							(start 0.2794 0.1778)
							(mid 0.249642 0.249642)
							(end 0.1778 0.2794)
						)
					)
					(width 0)
					(fill yes)
				)
			)
		)
	)
	(footprint ""
		(layer "B.Cu")
		(at 27.9654 -184.8866 -90)
		(property "Reference" "R443"
			(at 0 0 90)
			(layer "B.SilkS")
			(hide yes)
			(effects
				(font
					(size 1.27 1.27)
				)
				(justify mirror)
			)
		)
		(property "Value" "0R2J-2-GP"
			(at -0.064008 -3.993896 270)
			(unlocked yes)
			(layer "B.Fab")
			(hide yes)
			(effects
				(font
					(size 1.016 1.016)
					(thickness 0.1524)
				)
				(justify mirror)
			)
		)
		(property "Device Type" "R402H16"
			(at -0.064008 -5.517896 270)
			(unlocked yes)
			(layer "B.Fab")
			(hide yes)
			(effects
				(font
					(size 1.016 1.016)
					(thickness 0.1524)
				)
				(justify mirror)
			)
		)
		(duplicate_pad_numbers_are_jumpers no)
		(fp_line
			(start -0.508 -0.9398)
			(end 0.508 -0.9398)
			(stroke
				(width 0.1524)
				(type default)
			)
			(layer "B.SilkS")
		)
		(fp_line
			(start 0.508 -0.9398)
			(end 0.508 0.9398)
			(stroke
				(width 0.1524)
				(type default)
			)
			(layer "B.SilkS")
		)
		(fp_rect
			(start 0.508 0.9398)
			(end -0.508 -0.9398)
			(stroke
				(width 0)
				(type default)
			)
			(fill no)
			(layer "B.CrtYd")
		)
		(fp_rect
			(start 0.508 0.9398)
			(end -0.508 -0.9398)
			(stroke
				(width 0)
				(type default)
			)
			(fill no)
			(layer "B.Fab")
		)
		(pad "1" smd custom
			(at 0 -0.4445 90)
			(size 0.1397 0.1397)
			(layers "B.Cu" "B.Mask" "B.Paste")
			(net "BMC_I2C5_D_PEB_DEVICE_SDA")
			(options
				(clearance outline)
				(anchor circle)
			)
			(primitives
				(gr_poly
					(pts
						(arc
							(start -0.1778 0.2794)
							(mid -0.249642 0.249642)
							(end -0.2794 0.1778)
						)
						(arc
							(start -0.2794 -0.1778)
							(mid -0.249642 -0.249642)
							(end -0.1778 -0.2794)
						)
						(arc
							(start 0.1778 -0.2794)
							(mid 0.249642 -0.249642)
							(end 0.2794 -0.1778)
						)
						(arc
							(start 0.2794 0.1778)
							(mid 0.249642 0.249642)
							(end 0.1778 0.2794)
						)
					)
					(width 0)
					(fill yes)
				)
			)
		)
		(pad "2" smd custom
			(at 0 0.4445 90)
			(size 0.1397 0.1397)
			(layers "B.Cu" "B.Mask" "B.Paste")
			(net "BMC_I2C5_D_PEB_SDA")
			(options
				(clearance outline)
				(anchor circle)
			)
			(primitives
				(gr_poly
					(pts
						(arc
							(start -0.1778 0.2794)
							(mid -0.249642 0.249642)
							(end -0.2794 0.1778)
						)
						(arc
							(start -0.2794 -0.1778)
							(mid -0.249642 -0.249642)
							(end -0.1778 -0.2794)
						)
						(arc
							(start 0.1778 -0.2794)
							(mid 0.249642 -0.249642)
							(end 0.2794 -0.1778)
						)
						(arc
							(start 0.2794 0.1778)
							(mid 0.249642 0.249642)
							(end 0.1778 0.2794)
						)
					)
					(width 0)
					(fill yes)
				)
			)
		)
	)
	(footprint ""
		(layer "B.Cu")
		(at 252.603 -53.992272 -90)
		(property "Reference" "C581"
			(at 0 0 90)
			(layer "B.SilkS")
			(hide yes)
			(effects
				(font
					(size 1.27 1.27)
				)
				(justify mirror)
			)
		)
		(property "Value" "SCD1U16V1KX-1-GP"
			(at 2.8321 -1.7399 270)
			(unlocked yes)
			(layer "B.Fab")
			(hide yes)
			(effects
				(font
					(size 1.016 1.016)
					(thickness 0.1524)
				)
				(justify mirror)
			)
		)
		(property "Device Type" "C0201H13"
			(at 2.8321 -3.2639 270)
			(unlocked yes)
			(layer "B.Fab")
			(hide yes)
			(effects
				(font
					(size 1.016 1.016)
					(thickness 0.1524)
				)
				(justify mirror)
			)
		)
		(duplicate_pad_numbers_are_jumpers no)
		(fp_rect
			(start 0.2794 0.6477)
			(end -0.2794 -0.6477)
			(stroke
				(width 0)
				(type default)
			)
			(fill no)
			(layer "B.CrtYd")
		)
		(fp_rect
			(start 0.2794 0.6477)
			(end -0.2794 -0.6477)
			(stroke
				(width 0)
				(type default)
			)
			(fill no)
			(layer "B.Fab")
		)
		(pad "1" smd custom
			(at 0 -0.2794 90)
			(size 0.0762 0.0762)
			(layers "B.Cu" "B.Mask" "B.Paste")
			(net "DUT_AVD_PCIE")
			(options
				(clearance outline)
				(anchor circle)
			)
			(primitives
				(gr_poly
					(pts
						(arc
							(start 0.1524 0.127)
							(mid 0.137521 0.162921)
							(end 0.1016 0.1778)
						)
						(arc
							(start -0.1016 0.1778)
							(mid -0.137521 0.162921)
							(end -0.1524 0.127)
						)
						(arc
							(start -0.1524 -0.127)
							(mid -0.137521 -0.162921)
							(end -0.1016 -0.1778)
						)
						(arc
							(start 0.1016 -0.1778)
							(mid 0.137521 -0.162921)
							(end 0.1524 -0.127)
						)
					)
					(width 0)
					(fill yes)
				)
			)
		)
		(pad "2" smd custom
			(at 0 0.2794 90)
			(size 0.0762 0.0762)
			(layers "B.Cu" "B.Mask" "B.Paste")
			(net "GND")
			(options
				(clearance outline)
				(anchor circle)
			)
			(primitives
				(gr_poly
					(pts
						(arc
							(start 0.1524 0.127)
							(mid 0.137521 0.162921)
							(end 0.1016 0.1778)
						)
						(arc
							(start -0.1016 0.1778)
							(mid -0.137521 0.162921)
							(end -0.1524 0.127)
						)
						(arc
							(start -0.1524 -0.127)
							(mid -0.137521 -0.162921)
							(end -0.1016 -0.1778)
						)
						(arc
							(start 0.1016 -0.1778)
							(mid 0.137521 -0.162921)
							(end 0.1524 -0.127)
						)
					)
					(width 0)
					(fill yes)
				)
			)
		)
	)
	(footprint ""
		(layer "B.Cu")
		(at 43.5102 -187.4012 180)
		(property "Reference" "R870"
			(at 0 0 0)
			(layer "B.SilkS")
			(hide yes)
			(effects
				(font
					(size 1.27 1.27)
				)
				(justify mirror)
			)
		)
		(property "Value" "0R2J-2-GP"
			(at -0.064008 -3.993896 180)
			(unlocked yes)
			(layer "B.Fab")
			(hide yes)
			(effects
				(font
					(size 1.016 1.016)
					(thickness 0.1524)
				)
				(justify mirror)
			)
		)
		(property "Device Type" "R402H16"
			(at -0.064008 -5.517896 180)
			(unlocked yes)
			(layer "B.Fab")
			(hide yes)
			(effects
				(font
					(size 1.016 1.016)
					(thickness 0.1524)
				)
				(justify mirror)
			)
		)
		(duplicate_pad_numbers_are_jumpers no)
		(fp_line
			(start 0.508 -0.9398)
			(end 0.508 0.9398)
			(stroke
				(width 0.1524)
				(type default)
			)
			(layer "B.SilkS")
		)
		(fp_line
			(start -0.508 -0.9398)
			(end 0.508 -0.9398)
			(stroke
				(width 0.1524)
				(type default)
			)
			(layer "B.SilkS")
		)
		(fp_rect
			(start 0.508 0.9398)
			(end -0.508 -0.9398)
			(stroke
				(width 0)
				(type default)
			)
			(fill no)
			(layer "B.CrtYd")
		)
		(fp_rect
			(start 0.508 0.9398)
			(end -0.508 -0.9398)
			(stroke
				(width 0)
				(type default)
			)
			(fill no)
			(layer "B.Fab")
		)
		(pad "1" smd custom
			(at 0 -0.4445)
			(size 0.1397 0.1397)
			(layers "B.Cu" "B.Mask" "B.Paste")
			(net "BMC_I2C9_CLKBUF2_SCL")
			(options
				(clearance outline)
				(anchor circle)
			)
			(primitives
				(gr_poly
					(pts
						(arc
							(start -0.1778 0.2794)
							(mid -0.249642 0.249642)
							(end -0.2794 0.1778)
						)
						(arc
							(start -0.2794 -0.1778)
							(mid -0.249642 -0.249642)
							(end -0.1778 -0.2794)
						)
						(arc
							(start 0.1778 -0.2794)
							(mid 0.249642 -0.249642)
							(end 0.2794 -0.1778)
						)
						(arc
							(start 0.2794 0.1778)
							(mid 0.249642 0.249642)
							(end 0.1778 0.2794)
						)
					)
					(width 0)
					(fill yes)
				)
			)
		)
		(pad "2" smd custom
			(at 0 0.4445)
			(size 0.1397 0.1397)
			(layers "B.Cu" "B.Mask" "B.Paste")
			(net "BUF_I2C9_CLKBUF2_SCL")
			(options
				(clearance outline)
				(anchor circle)
			)
			(primitives
				(gr_poly
					(pts
						(arc
							(start -0.1778 0.2794)
							(mid -0.249642 0.249642)
							(end -0.2794 0.1778)
						)
						(arc
							(start -0.2794 -0.1778)
							(mid -0.249642 -0.249642)
							(end -0.1778 -0.2794)
						)
						(arc
							(start 0.1778 -0.2794)
							(mid 0.249642 -0.249642)
							(end 0.2794 -0.1778)
						)
						(arc
							(start 0.2794 0.1778)
							(mid 0.249642 0.249642)
							(end 0.1778 0.2794)
						)
					)
					(width 0)
					(fill yes)
				)
			)
		)
	)
	(footprint ""
		(layer "B.Cu")
		(at 34.9504 -127.339852)
		(property "Reference" "TP107"
			(at 0 0 0)
			(layer "B.SilkS")
			(hide yes)
			(effects
				(font
					(size 1.27 1.27)
				)
				(justify mirror)
			)
		)
		(property "Value" "TPAD28-2-GP"
			(at 0.0127 -1.6637 0)
			(unlocked yes)
			(layer "B.Fab")
			(hide yes)
			(effects
				(font
					(size 1.016 1.016)
					(thickness 0.1524)
				)
				(justify mirror)
			)
		)
		(property "Device Type" "TPAD28"
			(at 0.0127 -3.1877 0)
			(unlocked yes)
			(layer "B.Fab")
			(hide yes)
			(effects
				(font
					(size 1.016 1.016)
					(thickness 0.1524)
				)
				(justify mirror)
			)
		)
		(duplicate_pad_numbers_are_jumpers no)
		(fp_poly
			(pts
				(arc
					(start 0.3556 0)
					(mid -0.3556 0)
					(end 0.3556 0)
				)
			)
			(stroke
				(width 0)
				(type default)
			)
			(fill no)
			(layer "B.CrtYd")
		)
		(fp_poly
			(pts
				(arc
					(start 0.6096 0)
					(mid -0.6096 0)
					(end 0.6096 0)
				)
			)
			(stroke
				(width 0)
				(type default)
			)
			(fill no)
			(layer "B.Fab")
		)
		(pad "1" smd circle
			(at 0 0 180)
			(size 0.7112 0.7112)
			(layers "B.Cu" "B.Mask" "B.Paste")
			(net "TP_GPIOB2")
		)
	)
	(footprint ""
		(layer "B.Cu")
		(at 233.5911 -35.0012 180)
		(property "Reference" "TP199"
			(at 0 0 0)
			(layer "B.SilkS")
			(hide yes)
			(effects
				(font
					(size 1.27 1.27)
				)
				(justify mirror)
			)
		)
		(property "Value" "TPAD28-2-GP"
			(at 0.0127 -1.6637 180)
			(unlocked yes)
			(layer "B.Fab")
			(hide yes)
			(effects
				(font
					(size 1.016 1.016)
					(thickness 0.1524)
				)
				(justify mirror)
			)
		)
		(property "Device Type" "TPAD28"
			(at 0.0127 -3.1877 180)
			(unlocked yes)
			(layer "B.Fab")
			(hide yes)
			(effects
				(font
					(size 1.016 1.016)
					(thickness 0.1524)
				)
				(justify mirror)
			)
		)
		(duplicate_pad_numbers_are_jumpers no)
		(fp_poly
			(pts
				(arc
					(start -0.3556 0)
					(mid 0.3556 0)
					(end -0.3556 0)
				)
			)
			(stroke
				(width 0)
				(type default)
			)
			(fill no)
			(layer "B.CrtYd")
		)
		(fp_poly
			(pts
				(arc
					(start -0.6096 0)
					(mid 0.6096 0)
					(end -0.6096 0)
				)
			)
			(stroke
				(width 0)
				(type default)
			)
			(fill no)
			(layer "B.Fab")
		)
		(pad "1" smd circle
			(at 0 0)
			(size 0.7112 0.7112)
			(layers "B.Cu" "B.Mask" "B.Paste")
			(net "RMII_TXD_1")
		)
	)
	(footprint ""
		(layer "B.Cu")
		(at 177.485802 -71.071232 90)
		(property "Reference" "PG29"
			(at 0 0 90)
			(layer "B.SilkS")
			(hide yes)
			(effects
				(font
					(size 1.27 1.27)
				)
				(justify mirror)
			)
		)
		(property "Value" "GAP-CLOSE-PWR-3-GP"
			(at -0.0254 -6.5786 90)
			(unlocked yes)
			(layer "B.Fab")
			(hide yes)
			(effects
				(font
					(size 1.016 1.016)
					(thickness 0.1524)
				)
				(justify mirror)
			)
		)
		(property "Device Type" "GAP-CLOSE-PWR-3"
			(at -0.0254 -8.255 90)
			(unlocked yes)
			(layer "B.Fab")
			(hide yes)
			(effects
				(font
					(size 1.016 1.016)
					(thickness 0.1524)
				)
				(justify mirror)
			)
		)
		(duplicate_pad_numbers_are_jumpers no)
		(fp_rect
			(start 0.7112 0.4572)
			(end -0.7112 -0.4572)
			(stroke
				(width 0)
				(type default)
			)
			(fill no)
			(layer "B.CrtYd")
		)
		(fp_poly
			(pts
				(xy 0.7112 -0.4572) (xy -0.7112 -0.4572) (xy -0.7112 0.4572) (xy 0.7112 0.4572)
			)
			(stroke
				(width 0)
				(type default)
			)
			(fill no)
			(layer "B.Fab")
		)
		(pad "1" smd rect
			(at 0.3048 0 270)
			(size 0.6604 0.762)
			(layers "B.Cu" "B.Mask" "B.Paste")
			(net "DUT_AVD_TX")
		)
		(pad "2" smd rect
			(at -0.3048 0 270)
			(size 0.6604 0.762)
			(layers "B.Cu" "B.Mask" "B.Paste")
			(net "P0V9")
		)
	)
	(footprint ""
		(layer "B.Cu")
		(at 310.007 -57.023 180)
		(property "Reference" "PG38"
			(at 0 0 0)
			(layer "B.SilkS")
			(hide yes)
			(effects
				(font
					(size 1.27 1.27)
				)
				(justify mirror)
			)
		)
		(property "Value" "GAP-CLOSE-PWR-3-GP"
			(at -0.0254 -6.5786 180)
			(unlocked yes)
			(layer "B.Fab")
			(hide yes)
			(effects
				(font
					(size 1.016 1.016)
					(thickness 0.1524)
				)
				(justify mirror)
			)
		)
		(property "Device Type" "GAP-CLOSE-PWR-3"
			(at -0.0254 -8.255 180)
			(unlocked yes)
			(layer "B.Fab")
			(hide yes)
			(effects
				(font
					(size 1.016 1.016)
					(thickness 0.1524)
				)
				(justify mirror)
			)
		)
		(duplicate_pad_numbers_are_jumpers no)
		(fp_rect
			(start 0.7112 0.4572)
			(end -0.7112 -0.4572)
			(stroke
				(width 0)
				(type default)
			)
			(fill no)
			(layer "B.CrtYd")
		)
		(fp_poly
			(pts
				(xy 0.7112 -0.4572) (xy -0.7112 -0.4572) (xy -0.7112 0.4572) (xy 0.7112 0.4572)
			)
			(stroke
				(width 0)
				(type default)
			)
			(fill no)
			(layer "B.Fab")
		)
		(pad "1" smd rect
			(at 0.3048 0)
			(size 0.6604 0.762)
			(layers "B.Cu" "B.Mask" "B.Paste")
			(net "DUT_VDD")
		)
		(pad "2" smd rect
			(at -0.3048 0)
			(size 0.6604 0.762)
			(layers "B.Cu" "B.Mask" "B.Paste")
			(net "P0V9_E")
		)
	)
	(footprint ""
		(layer "B.Cu")
		(at 42.126154 -158.987744 180)
		(property "Reference" "C182"
			(at 0 0 0)
			(layer "B.SilkS")
			(hide yes)
			(effects
				(font
					(size 1.27 1.27)
				)
				(justify mirror)
			)
		)
		(property "Value" "SCD1U16V2KX-3GP"
			(at -1.1811 -2.7051 180)
			(unlocked yes)
			(layer "B.Fab")
			(hide yes)
			(effects
				(font
					(size 1.016 1.016)
					(thickness 0.1524)
				)
				(justify mirror)
			)
		)
		(property "Device Type" "C402H22"
			(at -1.1811 -4.2291 180)
			(unlocked yes)
			(layer "B.Fab")
			(hide yes)
			(effects
				(font
					(size 1.016 1.016)
					(thickness 0.1524)
				)
				(justify mirror)
			)
		)
		(duplicate_pad_numbers_are_jumpers no)
		(fp_rect
			(start 0.4318 0.9525)
			(end -0.4318 -0.9525)
			(stroke
				(width 0)
				(type default)
			)
			(fill no)
			(layer "B.CrtYd")
		)
		(fp_rect
			(start 0.4318 0.9525)
			(end -0.4318 -0.9525)
			(stroke
				(width 0)
				(type default)
			)
			(fill no)
			(layer "B.Fab")
		)
		(pad "1" smd custom
			(at 0 -0.4445)
			(size 0.1524 0.1524)
			(layers "B.Cu" "B.Mask" "B.Paste")
			(net "P1V53_STBY")
			(options
				(clearance outline)
				(anchor circle)
			)
			(primitives
				(gr_poly
					(pts
						(arc
							(start 0.3048 0.2032)
							(mid 0.275042 0.275042)
							(end 0.2032 0.3048)
						)
						(arc
							(start -0.2032 0.3048)
							(mid -0.275042 0.275042)
							(end -0.3048 0.2032)
						)
						(arc
							(start -0.3048 -0.2032)
							(mid -0.275042 -0.275042)
							(end -0.2032 -0.3048)
						)
						(arc
							(start 0.2032 -0.3048)
							(mid 0.275042 -0.275042)
							(end 0.3048 -0.2032)
						)
					)
					(width 0)
					(fill yes)
				)
			)
		)
		(pad "2" smd custom
			(at 0 0.4445)
			(size 0.1524 0.1524)
			(layers "B.Cu" "B.Mask" "B.Paste")
			(net "GND")
			(options
				(clearance outline)
				(anchor circle)
			)
			(primitives
				(gr_poly
					(pts
						(arc
							(start 0.3048 0.2032)
							(mid 0.275042 0.275042)
							(end 0.2032 0.3048)
						)
						(arc
							(start -0.2032 0.3048)
							(mid -0.275042 0.275042)
							(end -0.3048 0.2032)
						)
						(arc
							(start -0.3048 -0.2032)
							(mid -0.275042 -0.275042)
							(end -0.2032 -0.3048)
						)
						(arc
							(start 0.2032 -0.3048)
							(mid 0.275042 -0.275042)
							(end 0.3048 -0.2032)
						)
					)
					(width 0)
					(fill yes)
				)
			)
		)
	)
)
